FILE_TYPE = MULTI_PHYS_TABLE;
PART 'SW_H67881001'
{====================================================================================================================================================================}
:PACK_TYPE|MATERIAL  |PART_NUMBER      = EnvComp |PART_NUMBER   |JEDEC_TYPE  |CLASS  |DESCRIPTION                              |HEIGHT      |COMPONENT_TYPE| LPID | SPEED_URL | Status |RPL| AML | Bus_Unit | Days ;
{====================================================================================================================================================================}
'SM'      | 'IC'     | 'H67881-001'(!) = ''      | 'H67881-001' | 'SSW4RPF'  | 'IC'  | 'CONN,SWIT,TACTILE,VT,SPST,1,25.0V,SMT' | '0.378 IN' | 'SMTOTHER'   | '3825' | 'http://speed.intel.com:8081/speed/module/pdm/item/pdm_item_detail_direct.asp?item_cde=H67881-001&item_rev=01&url_param=unused' | '' | '' | '' | '' | '' 
'SM'      | 'EMPTY'  | 'H67881-001'(!) = ''      | 'H67881-001' | 'SSW4RPF'  | 'IO'  | 'CONN,SWIT,TACTILE,VT,SPST,1,25.0V,SMT' | '0.378 IN' | 'SMTOTHER'   | '3825' | 'http://speed.intel.com:8081/speed/module/pdm/item/pdm_item_detail_direct.asp?item_cde=H67881-001&item_rev=01&url_param=unused' | '' | '' | '' | '' | '' 
END_PART
END.
